# BASEBOARD_FAB2 (Tioga Pass) — schematic netlist excerpt (pin names and nets, part order shuffled) for the footprints in the layout excerpt that follows; sources: Cadence DE-HDL packaged netlist, KiCad conversion of Wiwynn_Tioga_Pass_MB.brd

C22W21  SC22U16V5MX-4-GP  20%  pkg SMD-BCG5  page 214 : \1\ = VR_FET_SW_P12V_STBY_PVCCIN_CPU0 ; \2\ = GND
R32W12  RES  0.0 5% CHIP  pkg 0402  page 185 : A = SMB_M2_ALT_N ; B = SMB_M2_ALT_R_N
R32W10  RES  0.0 5% CHIP  pkg 0402  page 185 : A = SMB_M2_SCL ; B = SMB_M2_SCL_R

(kicad_pcb
	(version 20260206)
	(generator "pcbnew")
	(generator_version "10.0")
	(general
		(thickness 1.6)
		(legacy_teardrops no)
	)
	(paper "A4")
	(title_block
		(title "Wiwynn_Tioga_Pass_MB.brd")
		(comment 1 "Tioga Pass / footprints 3314-3316 of 4770")
	)
	(layers
		(0 "F.Cu" signal "TOP")
		(4 "In1.Cu" signal "L2GND")
		(6 "In2.Cu" signal "L3")
		(8 "In3.Cu" signal "L4GND")
		(10 "In4.Cu" signal "L5")
		(12 "In5.Cu" signal "L6GND")
		(14 "In6.Cu" signal "L7VCC")
		(16 "In7.Cu" signal "L8VCC")
		(18 "In8.Cu" signal "L9GND")
		(20 "In9.Cu" signal "L10")
		(22 "In10.Cu" signal "L11GND")
		(24 "In11.Cu" signal "L12")
		(26 "In12.Cu" signal "L13GND")
		(2 "B.Cu" signal "BOTTOM")
		(9 "F.Adhes" user "F.Adhesive")
		(11 "B.Adhes" user "B.Adhesive")
		(13 "F.Paste" user "Package Geometry/Pastemask Top")
		(15 "B.Paste" user "Package Geometry/Pastemask Bottom")
		(5 "F.SilkS" user "Ref Des/Silkscreen Top")
		(7 "B.SilkS" user "Ref Des/Silkscreen Bottom")
		(1 "F.Mask" user "Board Geometry/Soldermask Top")
		(3 "B.Mask" user "Board Geometry/Soldermask Bottom")
		(17 "Dwgs.User" user "User.Drawings")
		(19 "Cmts.User" user "User.Comments")
		(21 "Eco1.User" user "User.Eco1")
		(23 "Eco2.User" user "User.Eco2")
		(25 "Edge.Cuts" user "Board Geometry/Outline")
		(27 "Margin" user)
		(31 "F.CrtYd" user "Package Geometry/Place Bound Top")
		(29 "B.CrtYd" user "Package Geometry/Place Bound Bottom")
		(35 "F.Fab" user "Ref Des/Assembly Top")
		(33 "B.Fab" user "Ref Des/Assembly Bottom")
	)
	(footprint ""
		(layer "B.Cu")
		(at 188.22797 -60.461144 180)
		(property "Reference" "C22W21"
			(at 0 0 0)
			(layer "B.SilkS")
			(hide yes)
			(effects
				(font
					(size 1.27 1.27)
				)
				(justify mirror)
			)
		)
		(property "Value" "*"
			(at 0.0762 -6.2357 180)
			(unlocked yes)
			(layer "B.Fab")
			(hide yes)
			(effects
				(font
					(size 1.27 1.016)
					(thickness 0.1524)
				)
				(justify mirror)
			)
		)
		(property "Device Type" "SC22U16V5MX-4-GP_SMD-BCG5-SC22A"
			(at 0.0762 -8.2677 180)
			(unlocked yes)
			(layer "B.Fab")
			(hide yes)
			(effects
				(font
					(size 1.27 1.016)
					(thickness 0.1524)
				)
				(justify mirror)
			)
		)
		(duplicate_pad_numbers_are_jumpers no)
		(fp_line
			(start -0.635 0)
			(end 0.635 0)
			(stroke
				(width 0.508)
				(type default)
			)
			(layer "B.SilkS")
		)
		(fp_rect
			(start 0.9652 1.778)
			(end -0.9652 -1.778)
			(stroke
				(width 0)
				(type default)
			)
			(fill no)
			(layer "B.CrtYd")
		)
		(fp_poly
			(pts
				(xy 0.9652 -1.778) (xy -0.9652 -1.778) (xy -0.9652 1.778) (xy 0.9652 1.778)
			)
			(stroke
				(width 0)
				(type default)
			)
			(fill no)
			(layer "B.Fab")
		)
		(pad "1" smd rect
			(at 0 -0.9652)
			(size 1.397 1.143)
			(layers "B.Cu" "B.Mask" "B.Paste")
			(net "VR_FET_SW_P12V_STBY_PVCCIN_CPU0")
		)
		(pad "2" smd rect
			(at 0 0.9652)
			(size 1.397 1.143)
			(layers "B.Cu" "B.Mask" "B.Paste")
			(net "GND")
		)
	)
	(footprint ""
		(layer "B.Cu")
		(at 386.309616 -13.04417)
		(property "Reference" "R32W12"
			(at 0.8382 -0.67818 0)
			(unlocked yes)
			(layer "B.SilkS")
			(effects
				(font
					(size 0.4064 0.254)
					(thickness 0.1524)
				)
				(justify left mirror)
			)
		)
		(property "Value" ""
			(at 0 0 0)
			(layer "B.Fab")
			(effects
				(font
					(size 1.27 1.27)
				)
				(justify mirror)
			)
		)
		(duplicate_pad_numbers_are_jumpers no)
		(fp_poly
			(pts
				(xy 0.2794 -0.1016) (xy -0.2794 -0.1016) (xy -0.2794 0.9906) (xy 0.2794 0.9906)
			)
			(stroke
				(width 0)
				(type default)
			)
			(fill no)
			(layer "B.CrtYd")
		)
		(fp_line
			(start -0.2794 -0.1016)
			(end 0.2794 -0.1016)
			(stroke
				(width 0.1)
				(type default)
			)
			(layer "B.Fab")
		)
		(fp_line
			(start -0.2794 0.9906)
			(end -0.2794 -0.1016)
			(stroke
				(width 0.1)
				(type default)
			)
			(layer "B.Fab")
		)
		(fp_line
			(start 0.2794 -0.1016)
			(end 0.2794 0.9906)
			(stroke
				(width 0.1)
				(type default)
			)
			(layer "B.Fab")
		)
		(fp_line
			(start 0.2794 0.9906)
			(end -0.2794 0.9906)
			(stroke
				(width 0.1)
				(type default)
			)
			(layer "B.Fab")
		)
		(pad "1" smd rect
			(at 0 0 180)
			(size 0.508 0.508)
			(layers "B.Cu" "B.Mask" "B.Paste")
			(net "SMB_M2_ALT_N")
		)
		(pad "2" smd rect
			(at 0 0.889 180)
			(size 0.508 0.508)
			(layers "B.Cu" "B.Mask" "B.Paste")
			(net "SMB_M2_ALT_R_N")
		)
		(zone
			(layer "B.Cu")
			(hatch none 0.5)
			(connect_pads
				(clearance 0)
			)
			(min_thickness 0.25)
			(keepout
				(tracks allowed)
				(vias not_allowed)
				(pads allowed)
				(copperpour not_allowed)
				(footprints allowed)
			)
			(placement
				(enabled no)
				(sheetname "")
			)
			(fill
				(thermal_gap 0.5)
				(thermal_bridge_width 0.5)
				(island_removal_mode 0)
			)
			(polygon
				(pts
					(xy 386.563616 -12.79017) (xy 386.055616 -12.79017) (xy 386.055616 -12.40917) (xy 386.563616 -12.40917)
				)
			)
		)
		(zone
			(layer "B.Cu")
			(hatch none 0.5)
			(connect_pads
				(clearance 0)
			)
			(min_thickness 0.25)
			(keepout
				(tracks not_allowed)
				(vias allowed)
				(pads allowed)
				(copperpour not_allowed)
				(footprints allowed)
			)
			(placement
				(enabled no)
				(sheetname "")
			)
			(fill
				(thermal_gap 0.5)
				(thermal_bridge_width 0.5)
				(island_removal_mode 0)
			)
			(polygon
				(pts
					(xy 386.563616 -12.40917) (xy 386.055616 -12.40917) (xy 386.055616 -12.79017) (xy 386.563616 -12.79017)
				)
			)
		)
	)
	(footprint ""
		(layer "B.Cu")
		(at 393.9667 -10.01903 180)
		(property "Reference" "R32W10"
			(at 0.8382 -0.67818 180)
			(unlocked yes)
			(layer "B.SilkS")
			(effects
				(font
					(size 0.4064 0.254)
					(thickness 0.1524)
				)
				(justify left mirror)
			)
		)
		(property "Value" ""
			(at 0 0 0)
			(layer "B.Fab")
			(effects
				(font
					(size 1.27 1.27)
				)
				(justify mirror)
			)
		)
		(duplicate_pad_numbers_are_jumpers no)
		(fp_poly
			(pts
				(xy 0.2794 -0.1016) (xy -0.2794 -0.1016) (xy -0.2794 0.9906) (xy 0.2794 0.9906)
			)
			(stroke
				(width 0)
				(type default)
			)
			(fill no)
			(layer "B.CrtYd")
		)
		(fp_line
			(start 0.2794 0.9906)
			(end -0.2794 0.9906)
			(stroke
				(width 0.1)
				(type default)
			)
			(layer "B.Fab")
		)
		(fp_line
			(start 0.2794 -0.1016)
			(end 0.2794 0.9906)
			(stroke
				(width 0.1)
				(type default)
			)
			(layer "B.Fab")
		)
		(fp_line
			(start -0.2794 0.9906)
			(end -0.2794 -0.1016)
			(stroke
				(width 0.1)
				(type default)
			)
			(layer "B.Fab")
		)
		(fp_line
			(start -0.2794 -0.1016)
			(end 0.2794 -0.1016)
			(stroke
				(width 0.1)
				(type default)
			)
			(layer "B.Fab")
		)
		(pad "1" smd rect
			(at 0 0)
			(size 0.508 0.508)
			(layers "B.Cu" "B.Mask" "B.Paste")
			(net "SMB_M2_SCL")
		)
		(pad "2" smd rect
			(at 0 0.889)
			(size 0.508 0.508)
			(layers "B.Cu" "B.Mask" "B.Paste")
			(net "SMB_M2_SCL_R")
		)
		(zone
			(layer "B.Cu")
			(hatch none 0.5)
			(connect_pads
				(clearance 0)
			)
			(min_thickness 0.25)
			(keepout
				(tracks not_allowed)
				(vias allowed)
				(pads allowed)
				(copperpour not_allowed)
				(footprints allowed)
			)
			(placement
				(enabled no)
				(sheetname "")
			)
			(fill
				(thermal_gap 0.5)
				(thermal_bridge_width 0.5)
				(island_removal_mode 0)
			)
			(polygon
				(pts
					(xy 393.7127 -10.65403) (xy 394.2207 -10.65403) (xy 394.2207 -10.27303) (xy 393.7127 -10.27303)
				)
			)
		)
		(zone
			(layer "B.Cu")
			(hatch none 0.5)
			(connect_pads
				(clearance 0)
			)
			(min_thickness 0.25)
			(keepout
				(tracks allowed)
				(vias not_allowed)
				(pads allowed)
				(copperpour not_allowed)
				(footprints allowed)
			)
			(placement
				(enabled no)
				(sheetname "")
			)
			(fill
				(thermal_gap 0.5)
				(thermal_bridge_width 0.5)
				(island_removal_mode 0)
			)
			(polygon
				(pts
					(xy 393.7127 -10.27303) (xy 394.2207 -10.27303) (xy 394.2207 -10.65403) (xy 393.7127 -10.65403)
				)
			)
		)
	)
)
